(kicad_pcb
	(version 20260206)
	(generator "pcbnew")
	(generator_version "10.0")
	(general
		(thickness 1.6)
		(legacy_teardrops no)
	)
	(paper "A4")
	(title_block
		(title "04192023_DAF0TMB3IC0_F0TG_MB_C_brd_V02_OCP.brd")
		(comment 1 "Grand Teton / footprints 894-899 of 8354")
	)
	(layers
		(0 "F.Cu" signal "TOP")
		(4 "In1.Cu" signal "GND")
		(6 "In2.Cu" signal "IN1")
		(8 "In3.Cu" signal "GND1")
		(10 "In4.Cu" signal "IN2")
		(12 "In5.Cu" signal "GND2")
		(14 "In6.Cu" signal "IN3")
		(16 "In7.Cu" signal "GND3")
		(18 "In8.Cu" signal "VCC")
		(20 "In9.Cu" signal "VCC1")
		(22 "In10.Cu" signal "GND4")
		(24 "In11.Cu" signal "IN4")
		(26 "In12.Cu" signal "GND5")
		(28 "In13.Cu" signal "IN5")
		(30 "In14.Cu" signal "GND6")
		(32 "In15.Cu" signal "IN6")
		(34 "In16.Cu" signal "GND7")
		(2 "B.Cu" signal "BOTTOM")
		(9 "F.Adhes" user "F.Adhesive")
		(11 "B.Adhes" user "B.Adhesive")
		(13 "F.Paste" user "Package Geometry/Pastemask Top")
		(15 "B.Paste" user "Package Geometry/Pastemask Bottom")
		(5 "F.SilkS" user "Ref Des/Silkscreen Top")
		(7 "B.SilkS" user "Ref Des/Silkscreen Bottom")
		(1 "F.Mask" user "Board Geometry/Soldermask Top")
		(3 "B.Mask" user "Board Geometry/Soldermask Bottom")
		(17 "Dwgs.User" user "User.Drawings")
		(19 "Cmts.User" user "User.Comments")
		(21 "Eco1.User" user "User.Eco1")
		(23 "Eco2.User" user "User.Eco2")
		(25 "Edge.Cuts" user "Board Geometry/Outline")
		(27 "Margin" user)
		(31 "F.CrtYd" user "Package Geometry/Place Bound Top")
		(29 "B.CrtYd" user "Package Geometry/Place Bound Bottom")
		(35 "F.Fab" user "Ref Des/Assembly Top")
		(33 "B.Fab" user "Ref Des/Assembly Bottom")
	)
	(footprint ""
		(layer "F.Cu")
		(at 61.845698 -26.99004 90)
		(property "Reference" "PR3852"
			(at 0 0 90)
			(layer "F.SilkS")
			(hide yes)
			(effects
				(font
					(size 1.27 1.27)
				)
			)
		)
		(property "Value" ""
			(at 0 0 90)
			(layer "F.Fab")
			(effects
				(font
					(size 1.27 1.27)
				)
			)
		)
		(duplicate_pad_numbers_are_jumpers no)
		(fp_line
			(start 0.7874 -0.4064)
			(end 0.7874 0.4064)
			(stroke
				(width 0.1524)
				(type default)
			)
			(layer "F.SilkS")
		)
		(fp_line
			(start -0.7874 -0.4064)
			(end 0.7874 -0.4064)
			(stroke
				(width 0.1524)
				(type default)
			)
			(layer "F.SilkS")
		)
		(fp_line
			(start 0.7874 0.4064)
			(end -0.7874 0.4064)
			(stroke
				(width 0.1524)
				(type default)
			)
			(layer "F.SilkS")
		)
		(fp_line
			(start -0.7874 0.4064)
			(end -0.7874 -0.4064)
			(stroke
				(width 0.1524)
				(type default)
			)
			(layer "F.SilkS")
		)
		(fp_line
			(start -0.12065 -0.305054)
			(end -0.12065 -0.2794)
			(stroke
				(width 0.1)
				(type default)
			)
			(layer "F.Fab")
		)
		(fp_line
			(start -0.67945 -0.305054)
			(end -0.12065 -0.305054)
			(stroke
				(width 0.1)
				(type default)
			)
			(layer "F.Fab")
		)
		(fp_line
			(start 0.67945 -0.3048)
			(end 0.67945 0.3048)
			(stroke
				(width 0.1)
				(type default)
			)
			(layer "F.Fab")
		)
		(fp_line
			(start 0.12065 -0.3048)
			(end 0.67945 -0.3048)
			(stroke
				(width 0.1)
				(type default)
			)
			(layer "F.Fab")
		)
		(fp_line
			(start 0.12065 -0.2794)
			(end 0.12065 -0.3048)
			(stroke
				(width 0.1)
				(type default)
			)
			(layer "F.Fab")
		)
		(fp_line
			(start -0.12065 -0.2794)
			(end 0.12065 -0.2794)
			(stroke
				(width 0.1)
				(type default)
			)
			(layer "F.Fab")
		)
		(fp_line
			(start 0.120396 0.2794)
			(end -0.12065 0.2794)
			(stroke
				(width 0.1)
				(type default)
			)
			(layer "F.Fab")
		)
		(fp_line
			(start -0.12065 0.2794)
			(end -0.12065 0.3048)
			(stroke
				(width 0.1)
				(type default)
			)
			(layer "F.Fab")
		)
		(fp_line
			(start 0.67945 0.3048)
			(end 0.120396 0.3048)
			(stroke
				(width 0.1)
				(type default)
			)
			(layer "F.Fab")
		)
		(fp_line
			(start 0.120396 0.3048)
			(end 0.120396 0.2794)
			(stroke
				(width 0.1)
				(type default)
			)
			(layer "F.Fab")
		)
		(fp_line
			(start -0.12065 0.3048)
			(end -0.67945 0.3048)
			(stroke
				(width 0.1)
				(type default)
			)
			(layer "F.Fab")
		)
		(fp_line
			(start -0.67945 0.3048)
			(end -0.67945 -0.305054)
			(stroke
				(width 0.1)
				(type default)
			)
			(layer "F.Fab")
		)
		(pad "1" smd circle
			(at -0.40005 0 90)
			(size 0 0)
			(layers "F.Cu" "F.Mask" "F.Paste")
			(net "P12V_OCP_V3_2")
		)
		(pad "2" smd circle
			(at 0.40005 0 90)
			(size 0 0)
			(layers "F.Cu" "F.Mask" "F.Paste")
			(net "P12V_OCP_OV_FB_2")
		)
	)
	(footprint ""
		(layer "F.Cu")
		(at 204.7621 -406.052782)
		(property "Reference" "PR3920"
			(at 0 0 0)
			(layer "F.SilkS")
			(hide yes)
			(effects
				(font
					(size 1.27 1.27)
				)
			)
		)
		(property "Value" ""
			(at 0 0 0)
			(layer "F.Fab")
			(effects
				(font
					(size 1.27 1.27)
				)
			)
		)
		(duplicate_pad_numbers_are_jumpers no)
		(fp_line
			(start -0.7874 -0.4064)
			(end 0.7874 -0.4064)
			(stroke
				(width 0.1524)
				(type default)
			)
			(layer "F.SilkS")
		)
		(fp_line
			(start -0.7874 0.4064)
			(end -0.7874 -0.4064)
			(stroke
				(width 0.1524)
				(type default)
			)
			(layer "F.SilkS")
		)
		(fp_line
			(start 0.7874 -0.4064)
			(end 0.7874 0.4064)
			(stroke
				(width 0.1524)
				(type default)
			)
			(layer "F.SilkS")
		)
		(fp_line
			(start 0.7874 0.4064)
			(end -0.7874 0.4064)
			(stroke
				(width 0.1524)
				(type default)
			)
			(layer "F.SilkS")
		)
		(fp_line
			(start -0.67945 -0.305054)
			(end -0.12065 -0.305054)
			(stroke
				(width 0.1)
				(type default)
			)
			(layer "F.Fab")
		)
		(fp_line
			(start -0.67945 0.3048)
			(end -0.67945 -0.305054)
			(stroke
				(width 0.1)
				(type default)
			)
			(layer "F.Fab")
		)
		(fp_line
			(start -0.12065 -0.305054)
			(end -0.12065 -0.2794)
			(stroke
				(width 0.1)
				(type default)
			)
			(layer "F.Fab")
		)
		(fp_line
			(start -0.12065 -0.2794)
			(end 0.12065 -0.2794)
			(stroke
				(width 0.1)
				(type default)
			)
			(layer "F.Fab")
		)
		(fp_line
			(start -0.12065 0.2794)
			(end -0.12065 0.3048)
			(stroke
				(width 0.1)
				(type default)
			)
			(layer "F.Fab")
		)
		(fp_line
			(start -0.12065 0.3048)
			(end -0.67945 0.3048)
			(stroke
				(width 0.1)
				(type default)
			)
			(layer "F.Fab")
		)
		(fp_line
			(start 0.120396 0.2794)
			(end -0.12065 0.2794)
			(stroke
				(width 0.1)
				(type default)
			)
			(layer "F.Fab")
		)
		(fp_line
			(start 0.120396 0.3048)
			(end 0.120396 0.2794)
			(stroke
				(width 0.1)
				(type default)
			)
			(layer "F.Fab")
		)
		(fp_line
			(start 0.12065 -0.3048)
			(end 0.67945 -0.3048)
			(stroke
				(width 0.1)
				(type default)
			)
			(layer "F.Fab")
		)
		(fp_line
			(start 0.12065 -0.2794)
			(end 0.12065 -0.3048)
			(stroke
				(width 0.1)
				(type default)
			)
			(layer "F.Fab")
		)
		(fp_line
			(start 0.67945 -0.3048)
			(end 0.67945 0.3048)
			(stroke
				(width 0.1)
				(type default)
			)
			(layer "F.Fab")
		)
		(fp_line
			(start 0.67945 0.3048)
			(end 0.120396 0.3048)
			(stroke
				(width 0.1)
				(type default)
			)
			(layer "F.Fab")
		)
		(pad "1" smd circle
			(at -0.40005 0)
			(size 0 0)
			(layers "F.Cu" "F.Mask" "F.Paste")
			(net "HSC_FLT_TYPE_1")
		)
		(pad "2" smd circle
			(at 0.40005 0)
			(size 0 0)
			(layers "F.Cu" "F.Mask" "F.Paste")
			(net "HSC_FLT_TYPE")
		)
	)
	(footprint ""
		(layer "F.Cu")
		(at 279.659842 -415.1376)
		(property "Reference" "R6865"
			(at 0 0 0)
			(layer "F.SilkS")
			(hide yes)
			(effects
				(font
					(size 1.27 1.27)
				)
			)
		)
		(property "Value" ""
			(at 0 0 0)
			(layer "F.Fab")
			(effects
				(font
					(size 1.27 1.27)
				)
			)
		)
		(duplicate_pad_numbers_are_jumpers no)
		(fp_line
			(start -0.7874 -0.4064)
			(end 0.7874 -0.4064)
			(stroke
				(width 0.1524)
				(type default)
			)
			(layer "F.SilkS")
		)
		(fp_line
			(start -0.7874 0.4064)
			(end -0.7874 -0.4064)
			(stroke
				(width 0.1524)
				(type default)
			)
			(layer "F.SilkS")
		)
		(fp_line
			(start 0.7874 -0.4064)
			(end 0.7874 0.4064)
			(stroke
				(width 0.1524)
				(type default)
			)
			(layer "F.SilkS")
		)
		(fp_line
			(start 0.7874 0.4064)
			(end -0.7874 0.4064)
			(stroke
				(width 0.1524)
				(type default)
			)
			(layer "F.SilkS")
		)
		(fp_line
			(start -0.67945 -0.305054)
			(end -0.12065 -0.305054)
			(stroke
				(width 0.1)
				(type default)
			)
			(layer "F.Fab")
		)
		(fp_line
			(start -0.67945 0.3048)
			(end -0.67945 -0.305054)
			(stroke
				(width 0.1)
				(type default)
			)
			(layer "F.Fab")
		)
		(fp_line
			(start -0.12065 -0.305054)
			(end -0.12065 -0.2794)
			(stroke
				(width 0.1)
				(type default)
			)
			(layer "F.Fab")
		)
		(fp_line
			(start -0.12065 -0.2794)
			(end 0.12065 -0.2794)
			(stroke
				(width 0.1)
				(type default)
			)
			(layer "F.Fab")
		)
		(fp_line
			(start -0.12065 0.2794)
			(end -0.12065 0.3048)
			(stroke
				(width 0.1)
				(type default)
			)
			(layer "F.Fab")
		)
		(fp_line
			(start -0.12065 0.3048)
			(end -0.67945 0.3048)
			(stroke
				(width 0.1)
				(type default)
			)
			(layer "F.Fab")
		)
		(fp_line
			(start 0.120396 0.2794)
			(end -0.12065 0.2794)
			(stroke
				(width 0.1)
				(type default)
			)
			(layer "F.Fab")
		)
		(fp_line
			(start 0.120396 0.3048)
			(end 0.120396 0.2794)
			(stroke
				(width 0.1)
				(type default)
			)
			(layer "F.Fab")
		)
		(fp_line
			(start 0.12065 -0.3048)
			(end 0.67945 -0.3048)
			(stroke
				(width 0.1)
				(type default)
			)
			(layer "F.Fab")
		)
		(fp_line
			(start 0.12065 -0.2794)
			(end 0.12065 -0.3048)
			(stroke
				(width 0.1)
				(type default)
			)
			(layer "F.Fab")
		)
		(fp_line
			(start 0.67945 -0.3048)
			(end 0.67945 0.3048)
			(stroke
				(width 0.1)
				(type default)
			)
			(layer "F.Fab")
		)
		(fp_line
			(start 0.67945 0.3048)
			(end 0.120396 0.3048)
			(stroke
				(width 0.1)
				(type default)
			)
			(layer "F.Fab")
		)
		(pad "1" smd circle
			(at -0.40005 0)
			(size 0 0)
			(layers "F.Cu" "F.Mask" "F.Paste")
			(net "SMB_HOST_CLK_3V3AUX_SDA_R1")
		)
		(pad "2" smd circle
			(at 0.40005 0)
			(size 0 0)
			(layers "F.Cu" "F.Mask" "F.Paste")
			(net "SMB_9ZXL045_P0_SDA")
		)
	)
	(footprint ""
		(layer "F.Cu")
		(at 257.242056 -114.84737 180)
		(property "Reference" "R3719"
			(at 0 0 180)
			(layer "F.SilkS")
			(hide yes)
			(effects
				(font
					(size 1.27 1.27)
				)
			)
		)
		(property "Value" ""
			(at 0 0 180)
			(layer "F.Fab")
			(effects
				(font
					(size 1.27 1.27)
				)
			)
		)
		(duplicate_pad_numbers_are_jumpers no)
		(fp_line
			(start 0.7874 0.4064)
			(end -0.7874 0.4064)
			(stroke
				(width 0.1524)
				(type default)
			)
			(layer "F.SilkS")
		)
		(fp_line
			(start 0.7874 -0.4064)
			(end 0.7874 0.4064)
			(stroke
				(width 0.1524)
				(type default)
			)
			(layer "F.SilkS")
		)
		(fp_line
			(start -0.7874 0.4064)
			(end -0.7874 -0.4064)
			(stroke
				(width 0.1524)
				(type default)
			)
			(layer "F.SilkS")
		)
		(fp_line
			(start -0.7874 -0.4064)
			(end 0.7874 -0.4064)
			(stroke
				(width 0.1524)
				(type default)
			)
			(layer "F.SilkS")
		)
		(fp_line
			(start 0.67945 0.3048)
			(end 0.120396 0.3048)
			(stroke
				(width 0.1)
				(type default)
			)
			(layer "F.Fab")
		)
		(fp_line
			(start 0.67945 -0.3048)
			(end 0.67945 0.3048)
			(stroke
				(width 0.1)
				(type default)
			)
			(layer "F.Fab")
		)
		(fp_line
			(start 0.12065 -0.2794)
			(end 0.12065 -0.3048)
			(stroke
				(width 0.1)
				(type default)
			)
			(layer "F.Fab")
		)
		(fp_line
			(start 0.12065 -0.3048)
			(end 0.67945 -0.3048)
			(stroke
				(width 0.1)
				(type default)
			)
			(layer "F.Fab")
		)
		(fp_line
			(start 0.120396 0.3048)
			(end 0.120396 0.2794)
			(stroke
				(width 0.1)
				(type default)
			)
			(layer "F.Fab")
		)
		(fp_line
			(start 0.120396 0.2794)
			(end -0.12065 0.2794)
			(stroke
				(width 0.1)
				(type default)
			)
			(layer "F.Fab")
		)
		(fp_line
			(start -0.12065 0.3048)
			(end -0.67945 0.3048)
			(stroke
				(width 0.1)
				(type default)
			)
			(layer "F.Fab")
		)
		(fp_line
			(start -0.12065 0.2794)
			(end -0.12065 0.3048)
			(stroke
				(width 0.1)
				(type default)
			)
			(layer "F.Fab")
		)
		(fp_line
			(start -0.12065 -0.2794)
			(end 0.12065 -0.2794)
			(stroke
				(width 0.1)
				(type default)
			)
			(layer "F.Fab")
		)
		(fp_line
			(start -0.12065 -0.305054)
			(end -0.12065 -0.2794)
			(stroke
				(width 0.1)
				(type default)
			)
			(layer "F.Fab")
		)
		(fp_line
			(start -0.67945 0.3048)
			(end -0.67945 -0.305054)
			(stroke
				(width 0.1)
				(type default)
			)
			(layer "F.Fab")
		)
		(fp_line
			(start -0.67945 -0.305054)
			(end -0.12065 -0.305054)
			(stroke
				(width 0.1)
				(type default)
			)
			(layer "F.Fab")
		)
		(pad "1" smd circle
			(at -0.40005 0 180)
			(size 0 0)
			(layers "F.Cu" "F.Mask" "F.Paste")
			(net "SMB_LM75_2_3V3AUX_SCL_R")
		)
		(pad "2" smd circle
			(at 0.40005 0 180)
			(size 0 0)
			(layers "F.Cu" "F.Mask" "F.Paste")
			(net "SMB_LM75_2_3V3AUX_SCL")
		)
	)
	(footprint ""
		(layer "F.Cu")
		(at 49.38268 -35.804348 180)
		(property "Reference" "R3206"
			(at 0 0 180)
			(layer "F.SilkS")
			(hide yes)
			(effects
				(font
					(size 1.27 1.27)
				)
			)
		)
		(property "Value" ""
			(at 0 0 180)
			(layer "F.Fab")
			(effects
				(font
					(size 1.27 1.27)
				)
			)
		)
		(duplicate_pad_numbers_are_jumpers no)
		(fp_line
			(start 0.7874 0.4064)
			(end -0.7874 0.4064)
			(stroke
				(width 0.1524)
				(type default)
			)
			(layer "F.SilkS")
		)
		(fp_line
			(start 0.7874 -0.4064)
			(end 0.7874 0.4064)
			(stroke
				(width 0.1524)
				(type default)
			)
			(layer "F.SilkS")
		)
		(fp_line
			(start -0.7874 0.4064)
			(end -0.7874 -0.4064)
			(stroke
				(width 0.1524)
				(type default)
			)
			(layer "F.SilkS")
		)
		(fp_line
			(start -0.7874 -0.4064)
			(end 0.7874 -0.4064)
			(stroke
				(width 0.1524)
				(type default)
			)
			(layer "F.SilkS")
		)
		(fp_line
			(start 0.67945 0.3048)
			(end 0.120396 0.3048)
			(stroke
				(width 0.1)
				(type default)
			)
			(layer "F.Fab")
		)
		(fp_line
			(start 0.67945 -0.3048)
			(end 0.67945 0.3048)
			(stroke
				(width 0.1)
				(type default)
			)
			(layer "F.Fab")
		)
		(fp_line
			(start 0.12065 -0.2794)
			(end 0.12065 -0.3048)
			(stroke
				(width 0.1)
				(type default)
			)
			(layer "F.Fab")
		)
		(fp_line
			(start 0.12065 -0.3048)
			(end 0.67945 -0.3048)
			(stroke
				(width 0.1)
				(type default)
			)
			(layer "F.Fab")
		)
		(fp_line
			(start 0.120396 0.3048)
			(end 0.120396 0.2794)
			(stroke
				(width 0.1)
				(type default)
			)
			(layer "F.Fab")
		)
		(fp_line
			(start 0.120396 0.2794)
			(end -0.12065 0.2794)
			(stroke
				(width 0.1)
				(type default)
			)
			(layer "F.Fab")
		)
		(fp_line
			(start -0.12065 0.3048)
			(end -0.67945 0.3048)
			(stroke
				(width 0.1)
				(type default)
			)
			(layer "F.Fab")
		)
		(fp_line
			(start -0.12065 0.2794)
			(end -0.12065 0.3048)
			(stroke
				(width 0.1)
				(type default)
			)
			(layer "F.Fab")
		)
		(fp_line
			(start -0.12065 -0.2794)
			(end 0.12065 -0.2794)
			(stroke
				(width 0.1)
				(type default)
			)
			(layer "F.Fab")
		)
		(fp_line
			(start -0.12065 -0.305054)
			(end -0.12065 -0.2794)
			(stroke
				(width 0.1)
				(type default)
			)
			(layer "F.Fab")
		)
		(fp_line
			(start -0.67945 0.3048)
			(end -0.67945 -0.305054)
			(stroke
				(width 0.1)
				(type default)
			)
			(layer "F.Fab")
		)
		(fp_line
			(start -0.67945 -0.305054)
			(end -0.12065 -0.305054)
			(stroke
				(width 0.1)
				(type default)
			)
			(layer "F.Fab")
		)
		(pad "1" smd circle
			(at -0.40005 0 180)
			(size 0 0)
			(layers "F.Cu" "F.Mask" "F.Paste")
			(net "FM_NCSI_OCP_V3_2_R_OE")
		)
		(pad "2" smd circle
			(at 0.40005 0 180)
			(size 0 0)
			(layers "F.Cu" "F.Mask" "F.Paste")
			(net "FB_BMC_ISOLATE1")
		)
	)
	(footprint ""
		(layer "F.Cu")
		(at 151.966676 -50.739294 90)
		(property "Reference" "R3591"
			(at 0 0 90)
			(layer "F.SilkS")
			(hide yes)
			(effects
				(font
					(size 1.27 1.27)
				)
			)
		)
		(property "Value" ""
			(at 0 0 90)
			(layer "F.Fab")
			(effects
				(font
					(size 1.27 1.27)
				)
			)
		)
		(duplicate_pad_numbers_are_jumpers no)
		(fp_line
			(start 0.7874 -0.4064)
			(end 0.7874 0.4064)
			(stroke
				(width 0.1524)
				(type default)
			)
			(layer "F.SilkS")
		)
		(fp_line
			(start -0.7874 -0.4064)
			(end 0.7874 -0.4064)
			(stroke
				(width 0.1524)
				(type default)
			)
			(layer "F.SilkS")
		)
		(fp_line
			(start 0.7874 0.4064)
			(end -0.7874 0.4064)
			(stroke
				(width 0.1524)
				(type default)
			)
			(layer "F.SilkS")
		)
		(fp_line
			(start -0.7874 0.4064)
			(end -0.7874 -0.4064)
			(stroke
				(width 0.1524)
				(type default)
			)
			(layer "F.SilkS")
		)
		(fp_line
			(start -0.12065 -0.305054)
			(end -0.12065 -0.2794)
			(stroke
				(width 0.1)
				(type default)
			)
			(layer "F.Fab")
		)
		(fp_line
			(start -0.67945 -0.305054)
			(end -0.12065 -0.305054)
			(stroke
				(width 0.1)
				(type default)
			)
			(layer "F.Fab")
		)
		(fp_line
			(start 0.67945 -0.3048)
			(end 0.67945 0.3048)
			(stroke
				(width 0.1)
				(type default)
			)
			(layer "F.Fab")
		)
		(fp_line
			(start 0.12065 -0.3048)
			(end 0.67945 -0.3048)
			(stroke
				(width 0.1)
				(type default)
			)
			(layer "F.Fab")
		)
		(fp_line
			(start 0.12065 -0.2794)
			(end 0.12065 -0.3048)
			(stroke
				(width 0.1)
				(type default)
			)
			(layer "F.Fab")
		)
		(fp_line
			(start -0.12065 -0.2794)
			(end 0.12065 -0.2794)
			(stroke
				(width 0.1)
				(type default)
			)
			(layer "F.Fab")
		)
		(fp_line
			(start 0.120396 0.2794)
			(end -0.12065 0.2794)
			(stroke
				(width 0.1)
				(type default)
			)
			(layer "F.Fab")
		)
		(fp_line
			(start -0.12065 0.2794)
			(end -0.12065 0.3048)
			(stroke
				(width 0.1)
				(type default)
			)
			(layer "F.Fab")
		)
		(fp_line
			(start 0.67945 0.3048)
			(end 0.120396 0.3048)
			(stroke
				(width 0.1)
				(type default)
			)
			(layer "F.Fab")
		)
		(fp_line
			(start 0.120396 0.3048)
			(end 0.120396 0.2794)
			(stroke
				(width 0.1)
				(type default)
			)
			(layer "F.Fab")
		)
		(fp_line
			(start -0.12065 0.3048)
			(end -0.67945 0.3048)
			(stroke
				(width 0.1)
				(type default)
			)
			(layer "F.Fab")
		)
		(fp_line
			(start -0.67945 0.3048)
			(end -0.67945 -0.305054)
			(stroke
				(width 0.1)
				(type default)
			)
			(layer "F.Fab")
		)
		(pad "1" smd circle
			(at -0.40005 0 90)
			(size 0 0)
			(layers "F.Cu" "F.Mask" "F.Paste")
			(net "SMB_INA230_3V3AUX_SDA")
		)
		(pad "2" smd circle
			(at 0.40005 0 90)
			(size 0 0)
			(layers "F.Cu" "F.Mask" "F.Paste")
			(net "SMB_INA230_3_3V3AUX_SDA_R")
		)
	)
)
